FILE_TYPE = MULTI_PHYS_TABLE;
PART 'PI3B3257A'
{=====================================================================================================================================================================}
:PACK_TYPE |MATERIAL|PART_NUMBER= EnvComp | PART_NUMBER|    JEDEC_TYPE  |DESCRIPTION|CLASS|   HEIGHT   |COMPONENT_TYPE|LEAD_LENGTH|LPID  | SPEED_URL | Status |RPL| AML | Bus_Unit | Days ;
{=====================================================================================================================================================================}
'TSSOPLF'    |'IC'    |'E16801-001'(!) = 'YES;YES;UNK;UNK;ok;VLD' |'E16801-001'|'QSOP16_15_25IA'|'quad mux' |'IC' | '0.068 IN' |  'SOIC'      |  ''|'976' | 'http://speed.intel.com:8081/speed/module/pdm/item/pdm_item_detail_direct.asp?item_cde=E16801-001&item_rev=01&url_param=unused' | 'Design' | 'NO' | '1' | 'SMO_IC' | '???' 
'TSSOPLF'    |'EMPTY' |'E16801-001'(!) = 'YES;YES;UNK;UNK;ok;VLD' |'E16801-001'|'QSOP16_15_25IA'|'quad mux' |'IO' | '0.068 IN' |  'SOIC'      |  ''|'976' | 'http://speed.intel.com:8081/speed/module/pdm/item/pdm_item_detail_direct.asp?item_cde=E16801-001&item_rev=01&url_param=unused' | 'Design' | 'NO' | '1' | 'SMO_IC' | '???' 
END_PART
END.
